FILE_TYPE = CONNECTIVITY;
{Allegro Design Entry HDL 17.4-2019 S026 (4007227) 1/17/2022}
"PAGE_NUMBER" = 438;
0"NC";
1"P5E_CPU1_P0_RX_DP<7:0>";
2"P5E_CPU1_P0_RX_DP<15:8>";
3"P5E_CPU1_P0_RX_DN<15:8>";
4"P5E_CPU1_P0_RX_DN<7:0>";
5"P5E_CPU1_P0_RX_DP<14>";
6"P5E_CPU1_P0_RX_DN<14>";
7"P5E_CPU1_P0_RX_DP<15>";
8"P5E_CPU1_P0_RX_DN<15>";
9"P5E_CPU1_P0_RX_DN<2>";
10"P5E_CPU1_P0_RX_DP<2>";
11"P5E_CPU1_P0_RX_DN<1>";
12"P5E_CPU1_P0_RX_DP<1>";
13"P5E_CPU1_P0_RX_DP<3>";
14"P5E_CPU1_P0_RX_DN<3>";
15"P5E_CPU1_P0_RX_DN<12>";
16"P5E_CPU1_P0_RX_DN<7>";
17"P5E_CPU1_P0_RX_DN<8>";
18"P5E_CPU1_P0_RX_DN<13>";
19"P5E_CPU1_P0_RX_DN<10>";
20"P5E_CPU1_P0_RX_DN<9>";
21"P5E_CPU1_P0_RX_DN<6>";
22"P5E_CPU1_P0_RX_DN<4>";
23"P5E_CPU1_P0_RX_DN<0>";
24"P5E_CPU1_P0_RX_DN<5>";
25"P5E_CPU1_P0_RX_DN<11>";
26"P5E_CPU1_P0_RX_DP<9>";
27"P5E_CPU1_P0_RX_DP<13>";
28"P5E_CPU1_P0_RX_DP<12>";
29"P5E_CPU1_P0_RX_DP<10>";
30"P5E_CPU1_P0_RX_DP<8>";
31"P5E_CPU1_P0_RX_DP<7>";
32"P5E_CPU1_P0_RX_DP<4>";
33"P5E_CPU1_P0_RX_DP<5>";
34"P5E_CPU1_P0_RX_DP<0>";
35"P5E_CPU1_P0_RX_DP<11>";
36"P5E_CPU1_P0_RX_DP<6>";
%"PT5161LRS"
"6","(-7575,4475)","0","pure_quanta","I1";
;
LOCATION"U6014"
$SEC"6"
CDS_SEC"6"
PART_TYPE"SMLF"
MATERIAL"IC"
VALUE"PT5161LRS"
NEEDS_NO_SIZE"TRUE"
CDS_LMAN_SYM_OUTLINE"-350,1450,300,-1400"
CDS_LIB"pure_quanta"
PART_NUMBER"AJ051610U03";
"A_PETN7"
$PN"CC29"17;
"A_PETP7"
$PN"CA26"30;
"A_PETN6"
$PN"BT29"20;
"A_PETP6"
$PN"BP26"26;
"A_PETN5"
$PN"BJ29"19;
"A_PETP5"
$PN"BG26"29;
"A_PETN4"
$PN"BB29"25;
"A_PETP4"
$PN"AY26"35;
"A_PETN3"
$PN"AR29"15;
"A_PETP3"
$PN"AN26"28;
"A_PETN2"
$PN"AH29"18;
"A_PETP2"
$PN"AF26"27;
"A_PETN1"
$PN"AA29"6;
"A_PETP1"
$PN"W26"5;
"A_PETN0"
$PN"P29"8;
"A_PETP0"
$PN"M26"7;
%"TAP"
"1","(-6550,4675)","0","standard","I10";
;
CDS_LIB"standard"
BODY_TYPE"PLUMBING"
HDL_TAP"TRUE";
"B \NAC \NWC"2;
"S \NAC"
BN"12"28;
%"TAP"
"1","(-6350,4575)","0","standard","I11";
;
CDS_LIB"standard"
BODY_TYPE"PLUMBING"
HDL_TAP"TRUE";
"B \NAC \NWC"3;
"S \NAC"
BN"12"15;
%"TAP"
"1","(-6550,5025)","0","standard","I12";
;
CDS_LIB"standard"
BODY_TYPE"PLUMBING"
HDL_TAP"TRUE";
"B \NAC \NWC"2;
"S \NAC"
BN"13"27;
%"TAP"
"1","(-6550,5375)","0","standard","I13";
;
CDS_LIB"standard"
BODY_TYPE"PLUMBING"
HDL_TAP"TRUE";
"B \NAC \NWC"2;
"S \NAC"
BN"14"5;
%"TAP"
"1","(-6350,4925)","0","standard","I14";
;
CDS_LIB"standard"
BODY_TYPE"PLUMBING"
HDL_TAP"TRUE";
"B \NAC \NWC"3;
"S \NAC"
BN"13"18;
%"TAP"
"1","(-6350,5275)","0","standard","I15";
;
CDS_LIB"standard"
BODY_TYPE"PLUMBING"
HDL_TAP"TRUE";
"B \NAC \NWC"3;
"S \NAC"
BN"14"6;
%"TAP"
"1","(-6550,5725)","0","standard","I16";
;
CDS_LIB"standard"
BODY_TYPE"PLUMBING"
HDL_TAP"TRUE";
"B \NAC \NWC"2;
"S \NAC"
BN"15"7;
%"TAP"
"1","(-6350,5625)","0","standard","I17";
;
CDS_LIB"standard"
BODY_TYPE"PLUMBING"
HDL_TAP"TRUE";
"B \NAC \NWC"3;
"S \NAC"
BN"15"8;
%"TAP"
"1","(-6550,3275)","0","standard","I2";
;
CDS_LIB"standard"
BODY_TYPE"PLUMBING"
HDL_TAP"TRUE";
"B \NAC \NWC"2;
"S \NAC"
BN"8"30;
%"TAP"
"1","(-2025,3350)","0","standard","I20";
;
CDS_LIB"standard"
BODY_TYPE"PLUMBING"
HDL_TAP"TRUE";
"B \NAC \NWC"1;
"S \NAC"
BN"0"34;
%"TAP"
"1","(-1825,3250)","0","standard","I21";
;
CDS_LIB"standard"
BODY_TYPE"PLUMBING"
HDL_TAP"TRUE";
"B \NAC \NWC"4;
"S \NAC"
BN"0"23;
%"TAP"
"1","(-1825,3600)","0","standard","I22";
;
CDS_LIB"standard"
BODY_TYPE"PLUMBING"
HDL_TAP"TRUE";
"B \NAC \NWC"4;
"S \NAC"
BN"1"11;
%"TAP"
"1","(-2025,3700)","0","standard","I23";
;
CDS_LIB"standard"
BODY_TYPE"PLUMBING"
HDL_TAP"TRUE";
"B \NAC \NWC"1;
"S \NAC"
BN"1"12;
%"TAP"
"1","(-2025,4050)","0","standard","I24";
;
CDS_LIB"standard"
BODY_TYPE"PLUMBING"
HDL_TAP"TRUE";
"B \NAC \NWC"1;
"S \NAC"
BN"2"10;
%"TAP"
"1","(-1825,3950)","0","standard","I25";
;
CDS_LIB"standard"
BODY_TYPE"PLUMBING"
HDL_TAP"TRUE";
"B \NAC \NWC"4;
"S \NAC"
BN"2"9;
%"TAP"
"1","(-1825,4300)","0","standard","I26";
;
CDS_LIB"standard"
BODY_TYPE"PLUMBING"
HDL_TAP"TRUE";
"B \NAC \NWC"4;
"S \NAC"
BN"3"14;
%"TAP"
"1","(-1825,4650)","0","standard","I27";
;
CDS_LIB"standard"
BODY_TYPE"PLUMBING"
HDL_TAP"TRUE";
"B \NAC \NWC"4;
"S \NAC"
BN"4"22;
%"TAP"
"1","(-2025,4400)","0","standard","I28";
;
CDS_LIB"standard"
BODY_TYPE"PLUMBING"
HDL_TAP"TRUE";
"B \NAC \NWC"1;
"S \NAC"
BN"3"13;
%"TAP"
"1","(-2025,4750)","0","standard","I29";
;
CDS_LIB"standard"
BODY_TYPE"PLUMBING"
HDL_TAP"TRUE";
"B \NAC \NWC"1;
"S \NAC"
BN"4"32;
%"TAP"
"1","(-6350,3175)","0","standard","I3";
;
CDS_LIB"standard"
BODY_TYPE"PLUMBING"
HDL_TAP"TRUE";
"B \NAC \NWC"3;
"S \NAC"
BN"8"17;
%"TAP"
"1","(-2025,5100)","0","standard","I30";
;
CDS_LIB"standard"
BODY_TYPE"PLUMBING"
HDL_TAP"TRUE";
"B \NAC \NWC"1;
"S \NAC"
BN"5"33;
%"TAP"
"1","(-1825,5000)","0","standard","I31";
;
CDS_LIB"standard"
BODY_TYPE"PLUMBING"
HDL_TAP"TRUE";
"B \NAC \NWC"4;
"S \NAC"
BN"5"24;
%"TAP"
"1","(-1825,5350)","0","standard","I32";
;
CDS_LIB"standard"
BODY_TYPE"PLUMBING"
HDL_TAP"TRUE";
"B \NAC \NWC"4;
"S \NAC"
BN"6"21;
%"TAP"
"1","(-2025,5450)","0","standard","I33";
;
CDS_LIB"standard"
BODY_TYPE"PLUMBING"
HDL_TAP"TRUE";
"B \NAC \NWC"1;
"S \NAC"
BN"6"36;
%"TAP"
"1","(-2025,5800)","0","standard","I34";
;
CDS_LIB"standard"
BODY_TYPE"PLUMBING"
HDL_TAP"TRUE";
"B \NAC \NWC"1;
"S \NAC"
BN"7"31;
%"TAP"
"1","(-1825,5700)","0","standard","I35";
;
CDS_LIB"standard"
BODY_TYPE"PLUMBING"
HDL_TAP"TRUE";
"B \NAC \NWC"4;
"S \NAC"
BN"7"16;
%"PT5161LRS"
"7","(-3050,4550)","0","pure_quanta","I38";
;
LOCATION"U6014"
$SEC"7"
CDS_SEC"7"
PART_TYPE"SMLF"
MATERIAL"IC"
VALUE"PT5161LRS"
CDS_LIB"pure_quanta"
CDS_LMAN_SYM_OUTLINE"-350,1450,300,-1400"
NEEDS_NO_SIZE"TRUE"
PART_NUMBER"AJ051610U03";
"A_PETN15"
$PN"EW29"23;
"A_PETP15"
$PN"EU26"34;
"A_PETN14"
$PN"EM29"11;
"A_PETP14"
$PN"EK26"12;
"A_PETN13"
$PN"EE29"9;
"A_PETP13"
$PN"EC26"10;
"A_PETN12"
$PN"DV29"14;
"A_PETP12"
$PN"DT26"13;
"A_PETN11"
$PN"DL29"22;
"A_PETP11"
$PN"DJ26"32;
"A_PETN10"
$PN"DD29"24;
"A_PETP10"
$PN"DB26"33;
"A_PETN9"
$PN"CU29"21;
"A_PETP9"
$PN"CR26"36;
"A_PETN8"
$PN"CK29"16;
"A_PETP8"
$PN"CH26"31;
%"TAP"
"1","(-6550,3625)","0","standard","I4";
;
CDS_LIB"standard"
BODY_TYPE"PLUMBING"
HDL_TAP"TRUE";
"B \NAC \NWC"2;
"S \NAC"
BN"9"26;
%"TAP"
"1","(-6350,3525)","0","standard","I5";
;
CDS_LIB"standard"
BODY_TYPE"PLUMBING"
HDL_TAP"TRUE";
"B \NAC \NWC"3;
"S \NAC"
BN"9"20;
%"TAP"
"1","(-6350,3875)","0","standard","I6";
;
CDS_LIB"standard"
BODY_TYPE"PLUMBING"
HDL_TAP"TRUE";
"B \NAC \NWC"3;
"S \NAC"
BN"10"19;
%"TAP"
"1","(-6550,3975)","0","standard","I7";
;
CDS_LIB"standard"
BODY_TYPE"PLUMBING"
HDL_TAP"TRUE";
"B \NAC \NWC"2;
"S \NAC"
BN"10"29;
%"TAP"
"1","(-6550,4325)","0","standard","I8";
;
CDS_LIB"standard"
BODY_TYPE"PLUMBING"
HDL_TAP"TRUE";
"B \NAC \NWC"2;
"S \NAC"
BN"11"35;
%"TAP"
"1","(-6350,4225)","0","standard","I9";
;
CDS_LIB"standard"
BODY_TYPE"PLUMBING"
HDL_TAP"TRUE";
"B \NAC \NWC"3;
"S \NAC"
BN"11"25;
END.
